# S9S_MB_2U (Grand Teton) — schematic netlist excerpt (pin names and nets, part order shuffled) for the footprints in the layout excerpt that follows; sources: Cadence DE-HDL packaged netlist, KiCad conversion of 03242023_DA0F0TMBIJ0_F0T_Motherboard_J_brd_V01_OCP.brd

R2505  Q_RES  33.2 1% CHIP  pkg 0402LF  page 115 : A = PWRGD_FAIL_CPU1_GH_R1 ; B = PWRGD_FAIL_CPU1_GH_R
R320  Q_RES  10K 1% CHIP  pkg 0402LF  page 80 : A = P3V3_AUX ; B = PU_S3M_CPU0_CPLD_CONFD

(kicad_pcb
	(version 20260206)
	(generator "pcbnew")
	(generator_version "10.0")
	(general
		(thickness 1.6)
		(legacy_teardrops no)
	)
	(paper "A4")
	(title_block
		(title "03242023_DA0F0TMBIJ0_F0T_Motherboard_J_brd_V01_OCP.brd")
		(comment 1 "Grand Teton / footprints 5469-5470 of 6105")
	)
	(layers
		(0 "F.Cu" signal "TOP")
		(4 "In1.Cu" signal "GND")
		(6 "In2.Cu" signal "IN1")
		(8 "In3.Cu" signal "GND1")
		(10 "In4.Cu" signal "IN2")
		(12 "In5.Cu" signal "GND2")
		(14 "In6.Cu" signal "IN3")
		(16 "In7.Cu" signal "GND3")
		(18 "In8.Cu" signal "VCC")
		(20 "In9.Cu" signal "VCC1")
		(22 "In10.Cu" signal "GND4")
		(24 "In11.Cu" signal "IN4")
		(26 "In12.Cu" signal "GND5")
		(28 "In13.Cu" signal "IN5")
		(30 "In14.Cu" signal "GND6")
		(32 "In15.Cu" signal "IN6")
		(34 "In16.Cu" signal "GND7")
		(2 "B.Cu" signal "BOTTOM")
		(9 "F.Adhes" user "F.Adhesive")
		(11 "B.Adhes" user "B.Adhesive")
		(13 "F.Paste" user "Package Geometry/Pastemask Top")
		(15 "B.Paste" user "Package Geometry/Pastemask Bottom")
		(5 "F.SilkS" user "Ref Des/Silkscreen Top")
		(7 "B.SilkS" user "Ref Des/Silkscreen Bottom")
		(1 "F.Mask" user "Board Geometry/Soldermask Top")
		(3 "B.Mask" user "Board Geometry/Soldermask Bottom")
		(17 "Dwgs.User" user "User.Drawings")
		(19 "Cmts.User" user "User.Comments")
		(21 "Eco1.User" user "User.Eco1")
		(23 "Eco2.User" user "User.Eco2")
		(25 "Edge.Cuts" user "Board Geometry/Outline")
		(27 "Margin" user)
		(31 "F.CrtYd" user "Package Geometry/Place Bound Top")
		(29 "B.CrtYd" user "Package Geometry/Place Bound Bottom")
		(35 "F.Fab" user "Ref Des/Assembly Top")
		(33 "B.Fab" user "Ref Des/Assembly Bottom")
	)
	(footprint ""
		(layer "B.Cu")
		(at 414.255712 -193.08953 -90)
		(property "Reference" "R320"
			(at 0 0 90)
			(layer "B.SilkS")
			(hide yes)
			(effects
				(font
					(size 1.27 1.27)
				)
				(justify mirror)
			)
		)
		(property "Value" ""
			(at 0 0 90)
			(layer "B.Fab")
			(effects
				(font
					(size 1.27 1.27)
				)
				(justify mirror)
			)
		)
		(duplicate_pad_numbers_are_jumpers no)
		(fp_line
			(start -0.7874 0.4064)
			(end 0.7874 0.4064)
			(stroke
				(width 0.1524)
				(type default)
			)
			(layer "B.SilkS")
		)
		(fp_line
			(start 0.7874 0.4064)
			(end 0.7874 -0.4064)
			(stroke
				(width 0.1524)
				(type default)
			)
			(layer "B.SilkS")
		)
		(fp_line
			(start -0.7874 -0.4064)
			(end -0.7874 0.4064)
			(stroke
				(width 0.1524)
				(type default)
			)
			(layer "B.SilkS")
		)
		(fp_line
			(start 0.7874 -0.4064)
			(end -0.7874 -0.4064)
			(stroke
				(width 0.1524)
				(type default)
			)
			(layer "B.SilkS")
		)
		(fp_line
			(start -0.67945 0.3048)
			(end -0.120396 0.3048)
			(stroke
				(width 0.1)
				(type default)
			)
			(layer "B.Fab")
		)
		(fp_line
			(start -0.120396 0.3048)
			(end -0.120396 0.2794)
			(stroke
				(width 0.1)
				(type default)
			)
			(layer "B.Fab")
		)
		(fp_line
			(start 0.12065 0.3048)
			(end 0.67945 0.3048)
			(stroke
				(width 0.1)
				(type default)
			)
			(layer "B.Fab")
		)
		(fp_line
			(start 0.67945 0.3048)
			(end 0.67945 -0.305054)
			(stroke
				(width 0.1)
				(type default)
			)
			(layer "B.Fab")
		)
		(fp_line
			(start -0.120396 0.2794)
			(end 0.12065 0.2794)
			(stroke
				(width 0.1)
				(type default)
			)
			(layer "B.Fab")
		)
		(fp_line
			(start 0.12065 0.2794)
			(end 0.12065 0.3048)
			(stroke
				(width 0.1)
				(type default)
			)
			(layer "B.Fab")
		)
		(fp_line
			(start -0.12065 -0.2794)
			(end -0.12065 -0.3048)
			(stroke
				(width 0.1)
				(type default)
			)
			(layer "B.Fab")
		)
		(fp_line
			(start 0.12065 -0.2794)
			(end -0.12065 -0.2794)
			(stroke
				(width 0.1)
				(type default)
			)
			(layer "B.Fab")
		)
		(fp_line
			(start -0.67945 -0.3048)
			(end -0.67945 0.3048)
			(stroke
				(width 0.1)
				(type default)
			)
			(layer "B.Fab")
		)
		(fp_line
			(start -0.12065 -0.3048)
			(end -0.67945 -0.3048)
			(stroke
				(width 0.1)
				(type default)
			)
			(layer "B.Fab")
		)
		(fp_line
			(start 0.12065 -0.305054)
			(end 0.12065 -0.2794)
			(stroke
				(width 0.1)
				(type default)
			)
			(layer "B.Fab")
		)
		(fp_line
			(start 0.67945 -0.305054)
			(end 0.12065 -0.305054)
			(stroke
				(width 0.1)
				(type default)
			)
			(layer "B.Fab")
		)
		(pad "1" smd circle
			(at 0.40005 0 90)
			(size 0 0)
			(layers "B.Cu" "B.Mask" "B.Paste")
			(net "P3V3_AUX")
		)
		(pad "2" smd circle
			(at -0.40005 0 90)
			(size 0 0)
			(layers "B.Cu" "B.Mask" "B.Paste")
			(net "PU_S3M_CPU0_CPLD_CONFD")
		)
	)
	(footprint ""
		(layer "B.Cu")
		(at 213.525354 -314.550044 90)
		(property "Reference" "R2505"
			(at 0 0 90)
			(layer "B.SilkS")
			(hide yes)
			(effects
				(font
					(size 1.27 1.27)
				)
				(justify mirror)
			)
		)
		(property "Value" ""
			(at 0 0 90)
			(layer "B.Fab")
			(effects
				(font
					(size 1.27 1.27)
				)
				(justify mirror)
			)
		)
		(duplicate_pad_numbers_are_jumpers no)
		(fp_line
			(start 0.7874 -0.4064)
			(end -0.7874 -0.4064)
			(stroke
				(width 0.1524)
				(type default)
			)
			(layer "B.SilkS")
		)
		(fp_line
			(start -0.7874 -0.4064)
			(end -0.7874 0.4064)
			(stroke
				(width 0.1524)
				(type default)
			)
			(layer "B.SilkS")
		)
		(fp_line
			(start 0.7874 0.4064)
			(end 0.7874 -0.4064)
			(stroke
				(width 0.1524)
				(type default)
			)
			(layer "B.SilkS")
		)
		(fp_line
			(start -0.7874 0.4064)
			(end 0.7874 0.4064)
			(stroke
				(width 0.1524)
				(type default)
			)
			(layer "B.SilkS")
		)
		(fp_line
			(start 0.67945 -0.305054)
			(end 0.12065 -0.305054)
			(stroke
				(width 0.1)
				(type default)
			)
			(layer "B.Fab")
		)
		(fp_line
			(start 0.12065 -0.305054)
			(end 0.12065 -0.2794)
			(stroke
				(width 0.1)
				(type default)
			)
			(layer "B.Fab")
		)
		(fp_line
			(start -0.12065 -0.3048)
			(end -0.67945 -0.3048)
			(stroke
				(width 0.1)
				(type default)
			)
			(layer "B.Fab")
		)
		(fp_line
			(start -0.67945 -0.3048)
			(end -0.67945 0.3048)
			(stroke
				(width 0.1)
				(type default)
			)
			(layer "B.Fab")
		)
		(fp_line
			(start 0.12065 -0.2794)
			(end -0.12065 -0.2794)
			(stroke
				(width 0.1)
				(type default)
			)
			(layer "B.Fab")
		)
		(fp_line
			(start -0.12065 -0.2794)
			(end -0.12065 -0.3048)
			(stroke
				(width 0.1)
				(type default)
			)
			(layer "B.Fab")
		)
		(fp_line
			(start 0.12065 0.2794)
			(end 0.12065 0.3048)
			(stroke
				(width 0.1)
				(type default)
			)
			(layer "B.Fab")
		)
		(fp_line
			(start -0.120396 0.2794)
			(end 0.12065 0.2794)
			(stroke
				(width 0.1)
				(type default)
			)
			(layer "B.Fab")
		)
		(fp_line
			(start 0.67945 0.3048)
			(end 0.67945 -0.305054)
			(stroke
				(width 0.1)
				(type default)
			)
			(layer "B.Fab")
		)
		(fp_line
			(start 0.12065 0.3048)
			(end 0.67945 0.3048)
			(stroke
				(width 0.1)
				(type default)
			)
			(layer "B.Fab")
		)
		(fp_line
			(start -0.120396 0.3048)
			(end -0.120396 0.2794)
			(stroke
				(width 0.1)
				(type default)
			)
			(layer "B.Fab")
		)
		(fp_line
			(start -0.67945 0.3048)
			(end -0.120396 0.3048)
			(stroke
				(width 0.1)
				(type default)
			)
			(layer "B.Fab")
		)
		(pad "1" smd circle
			(at 0.40005 0 270)
			(size 0 0)
			(layers "B.Cu" "B.Mask" "B.Paste")
			(net "PWRGD_FAIL_CPU1_GH_R1")
		)
		(pad "2" smd circle
			(at -0.40005 0 270)
			(size 0 0)
			(layers "B.Cu" "B.Mask" "B.Paste")
			(net "PWRGD_FAIL_CPU1_GH_R")
		)
	)
)
